(kicad_pcb
	(version 20260206)
	(generator "pcbnew")
	(generator_version "10.0")
	(general
		(thickness 1.6)
		(legacy_teardrops no)
	)
	(paper "A4")
	(title_block
		(title "Wiwynn_Tioga_Pass_MB.brd")
		(comment 1 "Tioga Pass / footprint 1465 of 4770 (J1F1), pads 1-71 of 76")
	)
	(layers
		(0 "F.Cu" signal "TOP")
		(4 "In1.Cu" signal "L2GND")
		(6 "In2.Cu" signal "L3")
		(8 "In3.Cu" signal "L4GND")
		(10 "In4.Cu" signal "L5")
		(12 "In5.Cu" signal "L6GND")
		(14 "In6.Cu" signal "L7VCC")
		(16 "In7.Cu" signal "L8VCC")
		(18 "In8.Cu" signal "L9GND")
		(20 "In9.Cu" signal "L10")
		(22 "In10.Cu" signal "L11GND")
		(24 "In11.Cu" signal "L12")
		(26 "In12.Cu" signal "L13GND")
		(2 "B.Cu" signal "BOTTOM")
		(9 "F.Adhes" user "F.Adhesive")
		(11 "B.Adhes" user "B.Adhesive")
		(13 "F.Paste" user "Package Geometry/Pastemask Top")
		(15 "B.Paste" user "Package Geometry/Pastemask Bottom")
		(5 "F.SilkS" user "Ref Des/Silkscreen Top")
		(7 "B.SilkS" user "Ref Des/Silkscreen Bottom")
		(1 "F.Mask" user "Board Geometry/Soldermask Top")
		(3 "B.Mask" user "Board Geometry/Soldermask Bottom")
		(17 "Dwgs.User" user "User.Drawings")
		(19 "Cmts.User" user "User.Comments")
		(21 "Eco1.User" user "User.Eco1")
		(23 "Eco2.User" user "User.Eco2")
		(25 "Edge.Cuts" user "Board Geometry/Outline")
		(27 "Margin" user)
		(31 "F.CrtYd" user "Package Geometry/Place Bound Top")
		(29 "B.CrtYd" user "Package Geometry/Place Bound Bottom")
		(35 "F.Fab" user "Ref Des/Assembly Top")
		(33 "B.Fab" user "Ref Des/Assembly Bottom")
	)
	(footprint ""
		(layer "F.Cu")
		(at 2.29997 -32.71012 -90)
		(property "Reference" "J1F1"
			(at 0 0 270)
			(layer "F.SilkS")
			(hide yes)
			(effects
				(font
					(size 1.27 1.27)
				)
			)
		)
		(property "Value" "*"
			(at -20.8026 -3.4036 270)
			(unlocked yes)
			(layer "F.Fab")
			(hide yes)
			(effects
				(font
					(size 1.27 1.016)
					(thickness 0.1524)
				)
			)
		)
		(property "Device Type" "DM-FCI-CONN76-8R-GP-U-01_CONN-A"
			(at -20.8026 -4.9276 270)
			(unlocked yes)
			(layer "F.Fab")
			(hide yes)
			(effects
				(font
					(size 1.27 1.016)
					(thickness 0.1524)
				)
			)
		)
		(duplicate_pad_numbers_are_jumpers no)
		(pad "A1" thru_hole circle
			(at -6.999986 6.199886 270)
			(size 0.8128 0.8128)
			(drill 0.399796)
			(layers "*.Cu" "*.Mask")
			(remove_unused_layers no)
			(net "P3E_CPU1_PE3_MP_RXN<0>")
			(clearance 0.2921)
			(thermal_gap 0.2921)
		)
		(pad "A2" thru_hole circle
			(at -4.99999 6.299962 270)
			(size 0.8636 0.8636)
			(drill 0.499872)
			(layers "*.Cu" "*.Mask")
			(remove_unused_layers no)
			(net "GND")
			(clearance 0.1778)
			(thermal_gap 0.1778)
		)
		(pad "A3" thru_hole circle
			(at -2.999994 6.199886 270)
			(size 0.8128 0.8128)
			(drill 0.399796)
			(layers "*.Cu" "*.Mask")
			(remove_unused_layers no)
			(net "P3E_CPU1_PE3_MP_RXP<6>")
			(clearance 0.2921)
			(thermal_gap 0.2921)
		)
		(pad "A4" thru_hole circle
			(at -0.999998 6.299962 270)
			(size 0.8636 0.8636)
			(drill 0.499872)
			(layers "*.Cu" "*.Mask")
			(remove_unused_layers no)
			(net "FAN_TACH3_R")
			(clearance 0.1778)
			(thermal_gap 0.1778)
		)
		(pad "A5" thru_hole circle
			(at 0.999998 6.199886 270)
			(size 0.8128 0.8128)
			(drill 0.399796)
			(layers "*.Cu" "*.Mask")
			(remove_unused_layers no)
			(net "NIC_MDI_MNG_TX_DP")
			(clearance 0.2921)
			(thermal_gap 0.2921)
		)
		(pad "A6" thru_hole circle
			(at 2.999994 6.299962 270)
			(size 0.8636 0.8636)
			(drill 0.499872)
			(layers "*.Cu" "*.Mask")
			(remove_unused_layers no)
			(net "IRQ_SML1_PMBUS_ALERT_R_N")
			(clearance 0.1778)
			(thermal_gap 0.1778)
		)
		(pad "A7" thru_hole circle
			(at 4.99999 6.199886 270)
			(size 0.8128 0.8128)
			(drill 0.399796)
			(layers "*.Cu" "*.Mask")
			(remove_unused_layers no)
			(net "P3E_CPU1_PE3_MP_C_TXN<3>")
			(clearance 0.2921)
			(thermal_gap 0.2921)
		)
		(pad "A8" thru_hole circle
			(at 6.999986 6.299962 270)
			(size 0.8636 0.8636)
			(drill 0.499872)
			(layers "*.Cu" "*.Mask")
			(remove_unused_layers no)
			(net "GND")
			(clearance 0.1778)
			(thermal_gap 0.1778)
		)
		(pad "B1" thru_hole circle
			(at -6.999986 4.800092 270)
			(size 0.8128 0.8128)
			(drill 0.399796)
			(layers "*.Cu" "*.Mask")
			(remove_unused_layers no)
			(net "P3E_CPU1_PE3_MP_RXP<0>")
			(clearance 0.2921)
			(thermal_gap 0.2921)
		)
		(pad "B2" thru_hole circle
			(at -4.99999 4.899914 270)
			(size 0.8128 0.8128)
			(drill 0.399796)
			(layers "*.Cu" "*.Mask")
			(remove_unused_layers no)
			(net "P3E_CPU1_PE3_MP_RXN<3>")
			(clearance 0.2921)
			(thermal_gap 0.2921)
		)
		(pad "B3" thru_hole circle
			(at -2.999994 4.800092 270)
			(size 0.8128 0.8128)
			(drill 0.399796)
			(layers "*.Cu" "*.Mask")
			(remove_unused_layers no)
			(net "P3E_CPU1_PE3_MP_RXN<6>")
			(clearance 0.2921)
			(thermal_gap 0.2921)
		)
		(pad "B4" thru_hole circle
			(at -0.999998 4.899914 270)
			(size 0.8128 0.8128)
			(drill 0.399796)
			(layers "*.Cu" "*.Mask")
			(remove_unused_layers no)
			(net "FAN_TACH2_R")
			(clearance 0.1524)
			(thermal_gap 0.1524)
		)
		(pad "B5" thru_hole circle
			(at 0.999998 4.800092 270)
			(size 0.8128 0.8128)
			(drill 0.399796)
			(layers "*.Cu" "*.Mask")
			(remove_unused_layers no)
			(net "NIC_MDI_MNG_TX_DN")
			(clearance 0.2921)
			(thermal_gap 0.2921)
		)
		(pad "B6" thru_hole circle
			(at 2.999994 4.899914 270)
			(size 0.8128 0.8128)
			(drill 0.399796)
			(layers "*.Cu" "*.Mask")
			(remove_unused_layers no)
			(net "SMB_BMC_PMBUS_STBY_LVC3_SDA")
			(clearance 0.1524)
			(thermal_gap 0.1524)
		)
		(pad "B7" thru_hole circle
			(at 4.99999 4.800092 270)
			(size 0.8128 0.8128)
			(drill 0.399796)
			(layers "*.Cu" "*.Mask")
			(remove_unused_layers no)
			(net "P3E_CPU1_PE3_MP_C_TXP<3>")
			(clearance 0.2921)
			(thermal_gap 0.2921)
		)
		(pad "B8" thru_hole circle
			(at 6.999986 4.899914 270)
			(size 0.8128 0.8128)
			(drill 0.399796)
			(layers "*.Cu" "*.Mask")
			(remove_unused_layers no)
			(net "P3E_CPU1_PE3_MP_C_TXN<0>")
			(clearance 0.2921)
			(thermal_gap 0.2921)
		)
		(pad "C1" thru_hole circle
			(at -6.999986 3.400044 270)
			(size 0.8636 0.8636)
			(drill 0.499872)
			(layers "*.Cu" "*.Mask")
			(remove_unused_layers no)
			(net "GND")
			(clearance 0.1778)
			(thermal_gap 0.1778)
		)
		(pad "C2" thru_hole circle
			(at -4.99999 3.50012 270)
			(size 0.8128 0.8128)
			(drill 0.399796)
			(layers "*.Cu" "*.Mask")
			(remove_unused_layers no)
			(net "P3E_CPU1_PE3_MP_RXP<3>")
			(clearance 0.2921)
			(thermal_gap 0.2921)
		)
		(pad "C3" thru_hole circle
			(at -2.999994 3.400044 270)
			(size 0.8636 0.8636)
			(drill 0.499872)
			(layers "*.Cu" "*.Mask")
			(remove_unused_layers no)
			(net "GND")
			(clearance 0.1778)
			(thermal_gap 0.1778)
		)
		(pad "C4" thru_hole circle
			(at -0.999998 3.50012 270)
			(size 0.8128 0.8128)
			(drill 0.399796)
			(layers "*.Cu" "*.Mask")
			(remove_unused_layers no)
			(net "FAN_TACH1_R")
			(clearance 0.1524)
			(thermal_gap 0.1524)
		)
		(pad "C5" thru_hole circle
			(at 0.999998 3.400044 270)
			(size 0.8636 0.8636)
			(drill 0.499872)
			(layers "*.Cu" "*.Mask")
			(remove_unused_layers no)
			(net "GND")
			(clearance 0.1778)
			(thermal_gap 0.1778)
		)
		(pad "C6" thru_hole circle
			(at 2.999994 3.50012 270)
			(size 0.8128 0.8128)
			(drill 0.399796)
			(layers "*.Cu" "*.Mask")
			(remove_unused_layers no)
			(net "SMB_BMC_PMBUS_STBY_LVC3_SCL")
			(clearance 0.1524)
			(thermal_gap 0.1524)
		)
		(pad "C7" thru_hole circle
			(at 4.99999 3.400044 270)
			(size 0.8636 0.8636)
			(drill 0.499872)
			(layers "*.Cu" "*.Mask")
			(remove_unused_layers no)
			(net "GND")
			(clearance 0.1778)
			(thermal_gap 0.1778)
		)
		(pad "C8" thru_hole circle
			(at 6.999986 3.50012 270)
			(size 0.8128 0.8128)
			(drill 0.399796)
			(layers "*.Cu" "*.Mask")
			(remove_unused_layers no)
			(net "P3E_CPU1_PE3_MP_C_TXP<0>")
			(clearance 0.2921)
			(thermal_gap 0.2921)
		)
		(pad "D1" thru_hole circle
			(at -6.999986 1.999996 270)
			(size 0.8128 0.8128)
			(drill 0.399796)
			(layers "*.Cu" "*.Mask")
			(remove_unused_layers no)
			(net "P3E_CPU1_PE3_MP_RXN<1>")
			(clearance 0.2921)
			(thermal_gap 0.2921)
		)
		(pad "D2" thru_hole circle
			(at -4.99999 2.100072 270)
			(size 0.8636 0.8636)
			(drill 0.499872)
			(layers "*.Cu" "*.Mask")
			(remove_unused_layers no)
			(net "GND")
			(clearance 0.1778)
			(thermal_gap 0.1778)
		)
		(pad "D3" thru_hole circle
			(at -2.999994 1.999996 270)
			(size 0.8128 0.8128)
			(drill 0.399796)
			(layers "*.Cu" "*.Mask")
			(remove_unused_layers no)
			(net "P3E_CPU1_PE3_MP_RXN<7>")
			(clearance 0.2921)
			(thermal_gap 0.2921)
		)
		(pad "D4" thru_hole circle
			(at -0.999998 2.100072 270)
			(size 0.8636 0.8636)
			(drill 0.499872)
			(layers "*.Cu" "*.Mask")
			(remove_unused_layers no)
			(net "FAN_TACH0_R")
			(clearance 0.1778)
			(thermal_gap 0.1778)
		)
		(pad "D5" thru_hole circle
			(at 0.999998 1.999996 270)
			(size 0.8128 0.8128)
			(drill 0.399796)
			(layers "*.Cu" "*.Mask")
			(remove_unused_layers no)
			(net "NIC_MDI_MNG_RX_DP")
			(clearance 0.2921)
			(thermal_gap 0.2921)
		)
		(pad "D6" thru_hole circle
			(at 2.999994 2.100072 270)
			(size 0.8636 0.8636)
			(drill 0.499872)
			(layers "*.Cu" "*.Mask")
			(remove_unused_layers no)
			(net "GND")
			(clearance 0.1778)
			(thermal_gap 0.1778)
		)
		(pad "D7" thru_hole circle
			(at 4.99999 1.999996 270)
			(size 0.8128 0.8128)
			(drill 0.399796)
			(layers "*.Cu" "*.Mask")
			(remove_unused_layers no)
			(net "P3E_CPU1_PE3_MP_C_TXN<4>")
			(clearance 0.2921)
			(thermal_gap 0.2921)
		)
		(pad "D8" thru_hole circle
			(at 6.999986 2.100072 270)
			(size 0.8636 0.8636)
			(drill 0.499872)
			(layers "*.Cu" "*.Mask")
			(remove_unused_layers no)
			(net "GND")
			(clearance 0.1778)
			(thermal_gap 0.1778)
		)
		(pad "E1" thru_hole circle
			(at -6.999986 0.599948 270)
			(size 0.8128 0.8128)
			(drill 0.399796)
			(layers "*.Cu" "*.Mask")
			(remove_unused_layers no)
			(net "P3E_CPU1_PE3_MP_RXP<1>")
			(clearance 0.2921)
			(thermal_gap 0.2921)
		)
		(pad "E2" thru_hole circle
			(at -4.99999 0.700024 270)
			(size 0.8128 0.8128)
			(drill 0.399796)
			(layers "*.Cu" "*.Mask")
			(remove_unused_layers no)
			(net "P3E_CPU1_PE3_MP_RXN<4>")
			(clearance 0.2921)
			(thermal_gap 0.2921)
		)
		(pad "E3" thru_hole circle
			(at -2.999994 0.599948 270)
			(size 0.8128 0.8128)
			(drill 0.399796)
			(layers "*.Cu" "*.Mask")
			(remove_unused_layers no)
			(net "P3E_CPU1_PE3_MP_RXP<7>")
			(clearance 0.2921)
			(thermal_gap 0.2921)
		)
		(pad "E4" thru_hole circle
			(at -0.999998 0.700024 270)
			(size 0.8128 0.8128)
			(drill 0.399796)
			(layers "*.Cu" "*.Mask")
			(remove_unused_layers no)
			(net "FM_MATED_IN_N")
			(clearance 0.1524)
			(thermal_gap 0.1524)
		)
		(pad "E5" thru_hole circle
			(at 0.999998 0.599948 270)
			(size 0.8128 0.8128)
			(drill 0.399796)
			(layers "*.Cu" "*.Mask")
			(remove_unused_layers no)
			(net "NIC_MDI_MNG_RX_DN")
			(clearance 0.2921)
			(thermal_gap 0.2921)
		)
		(pad "E6" thru_hole circle
			(at 2.999994 0.700024 270)
			(size 0.8128 0.8128)
			(drill 0.399796)
			(layers "*.Cu" "*.Mask")
			(remove_unused_layers no)
			(net "P3E_CPU1_PE3_MP_C_TXN<6>")
			(clearance 0.2921)
			(thermal_gap 0.2921)
		)
		(pad "E7" thru_hole circle
			(at 4.99999 0.599948 270)
			(size 0.8128 0.8128)
			(drill 0.399796)
			(layers "*.Cu" "*.Mask")
			(remove_unused_layers no)
			(net "P3E_CPU1_PE3_MP_C_TXP<4>")
			(clearance 0.2921)
			(thermal_gap 0.2921)
		)
		(pad "E8" thru_hole circle
			(at 6.999986 0.700024 270)
			(size 0.8128 0.8128)
			(drill 0.399796)
			(layers "*.Cu" "*.Mask")
			(remove_unused_layers no)
			(net "P3E_CPU1_PE3_MP_C_TXN<1>")
			(clearance 0.2921)
			(thermal_gap 0.2921)
		)
		(pad "F1" thru_hole circle
			(at -6.999986 -0.8001 270)
			(size 0.8636 0.8636)
			(drill 0.499872)
			(layers "*.Cu" "*.Mask")
			(remove_unused_layers no)
			(net "GND")
			(clearance 0.1778)
			(thermal_gap 0.1778)
		)
		(pad "F2" thru_hole circle
			(at -4.99999 -0.700024 270)
			(size 0.8128 0.8128)
			(drill 0.399796)
			(layers "*.Cu" "*.Mask")
			(remove_unused_layers no)
			(net "P3E_CPU1_PE3_MP_RXP<4>")
			(clearance 0.2921)
			(thermal_gap 0.2921)
		)
		(pad "F3" thru_hole circle
			(at -2.999994 -0.8001 270)
			(size 0.8636 0.8636)
			(drill 0.499872)
			(layers "*.Cu" "*.Mask")
			(remove_unused_layers no)
			(net "GND")
			(clearance 0.1778)
			(thermal_gap 0.1778)
		)
		(pad "F4" thru_hole circle
			(at -0.999998 -0.700024 270)
			(size 0.8128 0.8128)
			(drill 0.399796)
			(layers "*.Cu" "*.Mask")
			(remove_unused_layers no)
			(net "FAN_PWM_OUT_SYS0_R1")
			(clearance 0.1524)
			(thermal_gap 0.1524)
		)
		(pad "F5" thru_hole circle
			(at 0.999998 -0.8001 270)
			(size 0.8636 0.8636)
			(drill 0.499872)
			(layers "*.Cu" "*.Mask")
			(remove_unused_layers no)
			(net "FM_MB_SLOT_ID0")
			(clearance 0.1778)
			(thermal_gap 0.1778)
		)
		(pad "F6" thru_hole circle
			(at 2.999994 -0.700024 270)
			(size 0.8128 0.8128)
			(drill 0.399796)
			(layers "*.Cu" "*.Mask")
			(remove_unused_layers no)
			(net "P3E_CPU1_PE3_MP_C_TXP<6>")
			(clearance 0.2921)
			(thermal_gap 0.2921)
		)
		(pad "F7" thru_hole circle
			(at 4.99999 -0.8001 270)
			(size 0.8636 0.8636)
			(drill 0.499872)
			(layers "*.Cu" "*.Mask")
			(remove_unused_layers no)
			(net "GND")
			(clearance 0.1778)
			(thermal_gap 0.1778)
		)
		(pad "F8" thru_hole circle
			(at 6.999986 -0.700024 270)
			(size 0.8128 0.8128)
			(drill 0.399796)
			(layers "*.Cu" "*.Mask")
			(remove_unused_layers no)
			(net "P3E_CPU1_PE3_MP_C_TXP<1>")
			(clearance 0.2921)
			(thermal_gap 0.2921)
		)
		(pad "G1" thru_hole circle
			(at -6.999986 -2.199894 270)
			(size 0.8128 0.8128)
			(drill 0.399796)
			(layers "*.Cu" "*.Mask")
			(remove_unused_layers no)
			(net "P3E_CPU1_PE3_MP_RXP<2>")
			(clearance 0.2921)
			(thermal_gap 0.2921)
		)
		(pad "G2" thru_hole circle
			(at -4.99999 -2.100072 270)
			(size 0.8636 0.8636)
			(drill 0.499872)
			(layers "*.Cu" "*.Mask")
			(remove_unused_layers no)
			(net "GND")
			(clearance 0.1778)
			(thermal_gap 0.1778)
		)
		(pad "G3" thru_hole circle
			(at -2.999994 -2.199894 270)
			(size 0.8128 0.8128)
			(drill 0.399796)
			(layers "*.Cu" "*.Mask")
			(remove_unused_layers no)
			(net "SPA_MID_DBG_TX_R")
			(clearance 0.1524)
			(thermal_gap 0.1524)
		)
		(pad "G4" thru_hole circle
			(at -0.999998 -2.100072 270)
			(size 0.8636 0.8636)
			(drill 0.499872)
			(layers "*.Cu" "*.Mask")
			(remove_unused_layers no)
			(net "GND")
			(clearance 0.1778)
			(thermal_gap 0.1778)
		)
		(pad "G5" thru_hole circle
			(at 0.999998 -2.199894 270)
			(size 0.8128 0.8128)
			(drill 0.399796)
			(layers "*.Cu" "*.Mask")
			(remove_unused_layers no)
			(net "FM_MB_SLOT_ID1")
			(clearance 0.1524)
			(thermal_gap 0.1524)
		)
		(pad "G6" thru_hole circle
			(at 2.999994 -2.100072 270)
			(size 0.8636 0.8636)
			(drill 0.499872)
			(layers "*.Cu" "*.Mask")
			(remove_unused_layers no)
			(net "GND")
			(clearance 0.1778)
			(thermal_gap 0.1778)
		)
		(pad "G7" thru_hole circle
			(at 4.99999 -2.199894 270)
			(size 0.8128 0.8128)
			(drill 0.399796)
			(layers "*.Cu" "*.Mask")
			(remove_unused_layers no)
			(net "P3E_CPU1_PE3_MP_C_TXP<5>")
			(clearance 0.2921)
			(thermal_gap 0.2921)
		)
		(pad "G8" thru_hole circle
			(at 6.999986 -2.100072 270)
			(size 0.8636 0.8636)
			(drill 0.499872)
			(layers "*.Cu" "*.Mask")
			(remove_unused_layers no)
			(net "GND")
			(clearance 0.1778)
			(thermal_gap 0.1778)
		)
		(pad "H1" thru_hole circle
			(at -6.999986 -3.599942 270)
			(size 0.8128 0.8128)
			(drill 0.399796)
			(layers "*.Cu" "*.Mask")
			(remove_unused_layers no)
			(net "P3E_CPU1_PE3_MP_RXN<2>")
			(clearance 0.2921)
			(thermal_gap 0.2921)
		)
		(pad "H2" thru_hole circle
			(at -4.99999 -3.50012 270)
			(size 0.8128 0.8128)
			(drill 0.399796)
			(layers "*.Cu" "*.Mask")
			(remove_unused_layers no)
			(net "P3E_CPU1_PE3_MP_RXP<5>")
			(clearance 0.2921)
			(thermal_gap 0.2921)
		)
		(pad "H3" thru_hole circle
			(at -2.999994 -3.599942 270)
			(size 0.8128 0.8128)
			(drill 0.399796)
			(layers "*.Cu" "*.Mask")
			(remove_unused_layers no)
			(net "SPA_MID_DBG_RX_R")
			(clearance 0.1524)
			(thermal_gap 0.1524)
		)
		(pad "H4" thru_hole circle
			(at -0.999998 -3.50012 270)
			(size 0.8128 0.8128)
			(drill 0.399796)
			(layers "*.Cu" "*.Mask")
			(remove_unused_layers no)
			(net "CLK_100M_AIRMAX8_PE1_DP")
			(clearance 0.2921)
			(thermal_gap 0.2921)
		)
		(pad "H5" thru_hole circle
			(at 0.999998 -3.599942 270)
			(size 0.8128 0.8128)
			(drill 0.399796)
			(layers "*.Cu" "*.Mask")
			(remove_unused_layers no)
			(net "FM_MB_SLOT_ID2")
			(clearance 0.1524)
			(thermal_gap 0.1524)
		)
		(pad "H6" thru_hole circle
			(at 2.999994 -3.50012 270)
			(size 0.8128 0.8128)
			(drill 0.399796)
			(layers "*.Cu" "*.Mask")
			(remove_unused_layers no)
			(net "P3E_CPU1_PE3_MP_C_TXP<7>")
			(clearance 0.2921)
			(thermal_gap 0.2921)
		)
		(pad "H7" thru_hole circle
			(at 4.99999 -3.599942 270)
			(size 0.8128 0.8128)
			(drill 0.399796)
			(layers "*.Cu" "*.Mask")
			(remove_unused_layers no)
			(net "P3E_CPU1_PE3_MP_C_TXN<5>")
			(clearance 0.2921)
			(thermal_gap 0.2921)
		)
		(pad "H8" thru_hole circle
			(at 6.999986 -3.50012 270)
			(size 0.8128 0.8128)
			(drill 0.399796)
			(layers "*.Cu" "*.Mask")
			(remove_unused_layers no)
			(net "P3E_CPU1_PE3_MP_C_TXN<2>")
			(clearance 0.2921)
			(thermal_gap 0.2921)
		)
		(pad "I1" thru_hole circle
			(at -6.999986 -4.99999 270)
			(size 0.8636 0.8636)
			(drill 0.499872)
			(layers "*.Cu" "*.Mask")
			(remove_unused_layers no)
			(net "GND")
			(clearance 0.1778)
			(thermal_gap 0.1778)
		)
		(pad "I2" thru_hole circle
			(at -4.99999 -4.899914 270)
			(size 0.8128 0.8128)
			(drill 0.399796)
			(layers "*.Cu" "*.Mask")
			(remove_unused_layers no)
			(net "P3E_CPU1_PE3_MP_RXN<5>")
			(clearance 0.2921)
			(thermal_gap 0.2921)
		)
		(pad "I3" thru_hole circle
			(at -2.999994 -4.99999 270)
			(size 0.8636 0.8636)
			(drill 0.499872)
			(layers "*.Cu" "*.Mask")
			(remove_unused_layers no)
			(net "FM_ENABLE_FAN_POWER")
			(clearance 0.1778)
			(thermal_gap 0.1778)
		)
		(pad "I4" thru_hole circle
			(at -0.999998 -4.899914 270)
			(size 0.8128 0.8128)
			(drill 0.399796)
			(layers "*.Cu" "*.Mask")
			(remove_unused_layers no)
			(net "CLK_100M_AIRMAX8_PE1_DN")
			(clearance 0.2921)
			(thermal_gap 0.2921)
		)
		(pad "I5" thru_hole circle
			(at 0.999998 -4.99999 270)
			(size 0.8636 0.8636)
			(drill 0.499872)
			(layers "*.Cu" "*.Mask")
			(remove_unused_layers no)
			(net "RST_PCIE_MIDPLANE_N")
			(clearance 0.1778)
			(thermal_gap 0.1778)
		)
		(pad "I6" thru_hole circle
			(at 2.999994 -4.899914 270)
			(size 0.8128 0.8128)
			(drill 0.399796)
			(layers "*.Cu" "*.Mask")
			(remove_unused_layers no)
			(net "P3E_CPU1_PE3_MP_C_TXN<7>")
			(clearance 0.2921)
			(thermal_gap 0.2921)
		)
		(pad "I7" thru_hole circle
			(at 4.99999 -4.99999 270)
			(size 0.8636 0.8636)
			(drill 0.499872)
			(layers "*.Cu" "*.Mask")
			(remove_unused_layers no)
			(net "GND")
			(clearance 0.1778)
			(thermal_gap 0.1778)
		)
	)
)
